# S9S_MB_2U (Grand Teton) — schematic netlist excerpt (pin names and nets, part order shuffled) for the footprints in the layout excerpt that follows; sources: Cadence DE-HDL packaged netlist, KiCad conversion of 03242023_DA0F0TMBIJ0_F0T_Motherboard_J_brd_V01_OCP.brd

R2376  Q_RES  0 5% CHIP  pkg 0402LF  page 266 : A = IRQ_PSYS_CRIT_N ; B = PVCCIN_CPU0_PIN_ALERT
R200  Q_RES  100 1% CHIP  pkg 0402LF  page 123 : A = PVNN_TERM_CPU0 ; B = H_CPU0_MEMTRIP_LVC1_R_N

(kicad_pcb
	(version 20260206)
	(generator "pcbnew")
	(generator_version "10.0")
	(general
		(thickness 1.6)
		(legacy_teardrops no)
	)
	(paper "A4")
	(title_block
		(title "03242023_DA0F0TMBIJ0_F0T_Motherboard_J_brd_V01_OCP.brd")
		(comment 1 "Grand Teton / footprints 1002-1003 of 6105")
	)
	(layers
		(0 "F.Cu" signal "TOP")
		(4 "In1.Cu" signal "GND")
		(6 "In2.Cu" signal "IN1")
		(8 "In3.Cu" signal "GND1")
		(10 "In4.Cu" signal "IN2")
		(12 "In5.Cu" signal "GND2")
		(14 "In6.Cu" signal "IN3")
		(16 "In7.Cu" signal "GND3")
		(18 "In8.Cu" signal "VCC")
		(20 "In9.Cu" signal "VCC1")
		(22 "In10.Cu" signal "GND4")
		(24 "In11.Cu" signal "IN4")
		(26 "In12.Cu" signal "GND5")
		(28 "In13.Cu" signal "IN5")
		(30 "In14.Cu" signal "GND6")
		(32 "In15.Cu" signal "IN6")
		(34 "In16.Cu" signal "GND7")
		(2 "B.Cu" signal "BOTTOM")
		(9 "F.Adhes" user "F.Adhesive")
		(11 "B.Adhes" user "B.Adhesive")
		(13 "F.Paste" user "Package Geometry/Pastemask Top")
		(15 "B.Paste" user "Package Geometry/Pastemask Bottom")
		(5 "F.SilkS" user "Ref Des/Silkscreen Top")
		(7 "B.SilkS" user "Ref Des/Silkscreen Bottom")
		(1 "F.Mask" user "Board Geometry/Soldermask Top")
		(3 "B.Mask" user "Board Geometry/Soldermask Bottom")
		(17 "Dwgs.User" user "User.Drawings")
		(19 "Cmts.User" user "User.Comments")
		(21 "Eco1.User" user "User.Eco1")
		(23 "Eco2.User" user "User.Eco2")
		(25 "Edge.Cuts" user "Board Geometry/Outline")
		(27 "Margin" user)
		(31 "F.CrtYd" user "Package Geometry/Place Bound Top")
		(29 "B.CrtYd" user "Package Geometry/Place Bound Bottom")
		(35 "F.Fab" user "Ref Des/Assembly Top")
		(33 "B.Fab" user "Ref Des/Assembly Bottom")
	)
	(footprint ""
		(layer "F.Cu")
		(at 348.393004 -360.012996)
		(property "Reference" "R2376"
			(at 0 0 0)
			(layer "F.SilkS")
			(hide yes)
			(effects
				(font
					(size 1.27 1.27)
				)
			)
		)
		(property "Value" ""
			(at 0 0 0)
			(layer "F.Fab")
			(effects
				(font
					(size 1.27 1.27)
				)
			)
		)
		(duplicate_pad_numbers_are_jumpers no)
		(fp_line
			(start -0.7874 -0.4064)
			(end 0.7874 -0.4064)
			(stroke
				(width 0.1524)
				(type default)
			)
			(layer "F.SilkS")
		)
		(fp_line
			(start -0.7874 0.4064)
			(end -0.7874 -0.4064)
			(stroke
				(width 0.1524)
				(type default)
			)
			(layer "F.SilkS")
		)
		(fp_line
			(start 0.7874 -0.4064)
			(end 0.7874 0.4064)
			(stroke
				(width 0.1524)
				(type default)
			)
			(layer "F.SilkS")
		)
		(fp_line
			(start 0.7874 0.4064)
			(end -0.7874 0.4064)
			(stroke
				(width 0.1524)
				(type default)
			)
			(layer "F.SilkS")
		)
		(fp_line
			(start -0.67945 -0.305054)
			(end -0.12065 -0.305054)
			(stroke
				(width 0.1)
				(type default)
			)
			(layer "F.Fab")
		)
		(fp_line
			(start -0.67945 0.3048)
			(end -0.67945 -0.305054)
			(stroke
				(width 0.1)
				(type default)
			)
			(layer "F.Fab")
		)
		(fp_line
			(start -0.12065 -0.305054)
			(end -0.12065 -0.2794)
			(stroke
				(width 0.1)
				(type default)
			)
			(layer "F.Fab")
		)
		(fp_line
			(start -0.12065 -0.2794)
			(end 0.12065 -0.2794)
			(stroke
				(width 0.1)
				(type default)
			)
			(layer "F.Fab")
		)
		(fp_line
			(start -0.12065 0.2794)
			(end -0.12065 0.3048)
			(stroke
				(width 0.1)
				(type default)
			)
			(layer "F.Fab")
		)
		(fp_line
			(start -0.12065 0.3048)
			(end -0.67945 0.3048)
			(stroke
				(width 0.1)
				(type default)
			)
			(layer "F.Fab")
		)
		(fp_line
			(start 0.120396 0.2794)
			(end -0.12065 0.2794)
			(stroke
				(width 0.1)
				(type default)
			)
			(layer "F.Fab")
		)
		(fp_line
			(start 0.120396 0.3048)
			(end 0.120396 0.2794)
			(stroke
				(width 0.1)
				(type default)
			)
			(layer "F.Fab")
		)
		(fp_line
			(start 0.12065 -0.3048)
			(end 0.67945 -0.3048)
			(stroke
				(width 0.1)
				(type default)
			)
			(layer "F.Fab")
		)
		(fp_line
			(start 0.12065 -0.2794)
			(end 0.12065 -0.3048)
			(stroke
				(width 0.1)
				(type default)
			)
			(layer "F.Fab")
		)
		(fp_line
			(start 0.67945 -0.3048)
			(end 0.67945 0.3048)
			(stroke
				(width 0.1)
				(type default)
			)
			(layer "F.Fab")
		)
		(fp_line
			(start 0.67945 0.3048)
			(end 0.120396 0.3048)
			(stroke
				(width 0.1)
				(type default)
			)
			(layer "F.Fab")
		)
		(pad "1" smd circle
			(at -0.40005 0)
			(size 0 0)
			(layers "F.Cu" "F.Mask" "F.Paste")
			(net "IRQ_PSYS_CRIT_N")
		)
		(pad "2" smd circle
			(at 0.40005 0)
			(size 0 0)
			(layers "F.Cu" "F.Mask" "F.Paste")
			(net "PVCCIN_CPU0_PIN_ALERT")
		)
	)
	(footprint ""
		(layer "F.Cu")
		(at 128.45288 -100.167948 -90)
		(property "Reference" "R200"
			(at 0 0 270)
			(layer "F.SilkS")
			(hide yes)
			(effects
				(font
					(size 1.27 1.27)
				)
			)
		)
		(property "Value" ""
			(at 0 0 270)
			(layer "F.Fab")
			(effects
				(font
					(size 1.27 1.27)
				)
			)
		)
		(duplicate_pad_numbers_are_jumpers no)
		(fp_line
			(start -0.7874 0.4064)
			(end -0.7874 -0.4064)
			(stroke
				(width 0.1524)
				(type default)
			)
			(layer "F.SilkS")
		)
		(fp_line
			(start 0.7874 0.4064)
			(end -0.7874 0.4064)
			(stroke
				(width 0.1524)
				(type default)
			)
			(layer "F.SilkS")
		)
		(fp_line
			(start -0.7874 -0.4064)
			(end 0.7874 -0.4064)
			(stroke
				(width 0.1524)
				(type default)
			)
			(layer "F.SilkS")
		)
		(fp_line
			(start 0.7874 -0.4064)
			(end 0.7874 0.4064)
			(stroke
				(width 0.1524)
				(type default)
			)
			(layer "F.SilkS")
		)
		(fp_line
			(start -0.67945 0.3048)
			(end -0.67945 -0.305054)
			(stroke
				(width 0.1)
				(type default)
			)
			(layer "F.Fab")
		)
		(fp_line
			(start -0.12065 0.3048)
			(end -0.67945 0.3048)
			(stroke
				(width 0.1)
				(type default)
			)
			(layer "F.Fab")
		)
		(fp_line
			(start 0.120396 0.3048)
			(end 0.120396 0.2794)
			(stroke
				(width 0.1)
				(type default)
			)
			(layer "F.Fab")
		)
		(fp_line
			(start 0.67945 0.3048)
			(end 0.120396 0.3048)
			(stroke
				(width 0.1)
				(type default)
			)
			(layer "F.Fab")
		)
		(fp_line
			(start -0.12065 0.2794)
			(end -0.12065 0.3048)
			(stroke
				(width 0.1)
				(type default)
			)
			(layer "F.Fab")
		)
		(fp_line
			(start 0.120396 0.2794)
			(end -0.12065 0.2794)
			(stroke
				(width 0.1)
				(type default)
			)
			(layer "F.Fab")
		)
		(fp_line
			(start -0.12065 -0.2794)
			(end 0.12065 -0.2794)
			(stroke
				(width 0.1)
				(type default)
			)
			(layer "F.Fab")
		)
		(fp_line
			(start 0.12065 -0.2794)
			(end 0.12065 -0.3048)
			(stroke
				(width 0.1)
				(type default)
			)
			(layer "F.Fab")
		)
		(fp_line
			(start 0.12065 -0.3048)
			(end 0.67945 -0.3048)
			(stroke
				(width 0.1)
				(type default)
			)
			(layer "F.Fab")
		)
		(fp_line
			(start 0.67945 -0.3048)
			(end 0.67945 0.3048)
			(stroke
				(width 0.1)
				(type default)
			)
			(layer "F.Fab")
		)
		(fp_line
			(start -0.67945 -0.305054)
			(end -0.12065 -0.305054)
			(stroke
				(width 0.1)
				(type default)
			)
			(layer "F.Fab")
		)
		(fp_line
			(start -0.12065 -0.305054)
			(end -0.12065 -0.2794)
			(stroke
				(width 0.1)
				(type default)
			)
			(layer "F.Fab")
		)
		(pad "1" smd circle
			(at -0.40005 0 270)
			(size 0 0)
			(layers "F.Cu" "F.Mask" "F.Paste")
			(net "PVNN_TERM_CPU0")
		)
		(pad "2" smd circle
			(at 0.40005 0 270)
			(size 0 0)
			(layers "F.Cu" "F.Mask" "F.Paste")
			(net "H_CPU0_MEMTRIP_LVC1_R_N")
		)
	)
)
